(kicad_pcb
	(version 20260206)
	(generator "pcbnew")
	(generator_version "10.0")
	(general
		(thickness 1.6)
		(legacy_teardrops no)
	)
	(paper "A4")
	(title_block
		(title "01162023_DA0F0TEBIF0_F0T_Expander_BD_F_brd_V02_OCP.brd")
		(comment 1 "Grand Teton / footprints 1969-1975 of 9728")
	)
	(layers
		(0 "F.Cu" signal "TOP")
		(4 "In1.Cu" signal "GND")
		(6 "In2.Cu" signal "VCC")
		(8 "In3.Cu" signal "VCC1")
		(10 "In4.Cu" signal "GND1")
		(12 "In5.Cu" signal "IN1")
		(14 "In6.Cu" signal "GND2")
		(16 "In7.Cu" signal "IN2")
		(18 "In8.Cu" signal "GND3")
		(20 "In9.Cu" signal "IN3")
		(22 "In10.Cu" signal "GND4")
		(24 "In11.Cu" signal "IN4")
		(26 "In12.Cu" signal "GND5")
		(28 "In13.Cu" signal "IN5")
		(30 "In14.Cu" signal "GND6")
		(32 "In15.Cu" signal "IN6")
		(34 "In16.Cu" signal "GND7")
		(2 "B.Cu" signal "BOTTOM")
		(9 "F.Adhes" user "F.Adhesive")
		(11 "B.Adhes" user "B.Adhesive")
		(13 "F.Paste" user "Package Geometry/Pastemask Top")
		(15 "B.Paste" user "Package Geometry/Pastemask Bottom")
		(5 "F.SilkS" user "Ref Des/Silkscreen Top")
		(7 "B.SilkS" user "Ref Des/Silkscreen Bottom")
		(1 "F.Mask" user "Board Geometry/Soldermask Top")
		(3 "B.Mask" user "Board Geometry/Soldermask Bottom")
		(17 "Dwgs.User" user "User.Drawings")
		(19 "Cmts.User" user "User.Comments")
		(21 "Eco1.User" user "User.Eco1")
		(23 "Eco2.User" user "User.Eco2")
		(25 "Edge.Cuts" user "Board Geometry/Outline")
		(27 "Margin" user)
		(31 "F.CrtYd" user "Package Geometry/Place Bound Top")
		(29 "B.CrtYd" user "Package Geometry/Place Bound Bottom")
		(35 "F.Fab" user "Ref Des/Assembly Top")
		(33 "B.Fab" user "Ref Des/Assembly Bottom")
	)
	(footprint ""
		(layer "F.Cu")
		(at 98.947224 -19.33956)
		(property "Reference" "C3899"
			(at 0 0 0)
			(layer "F.SilkS")
			(hide yes)
			(effects
				(font
					(size 1.27 1.27)
				)
			)
		)
		(property "Value" ""
			(at 0 0 0)
			(layer "F.Fab")
			(effects
				(font
					(size 1.27 1.27)
				)
			)
		)
		(duplicate_pad_numbers_are_jumpers no)
		(fp_line
			(start -0.7874 -0.4064)
			(end 0.7874 -0.4064)
			(stroke
				(width 0.1524)
				(type default)
			)
			(layer "F.SilkS")
		)
		(fp_line
			(start -0.7874 0.4064)
			(end -0.7874 -0.4064)
			(stroke
				(width 0.1524)
				(type default)
			)
			(layer "F.SilkS")
		)
		(fp_line
			(start 0.7874 -0.4064)
			(end 0.7874 0.4064)
			(stroke
				(width 0.1524)
				(type default)
			)
			(layer "F.SilkS")
		)
		(fp_line
			(start 0.7874 0.4064)
			(end -0.7874 0.4064)
			(stroke
				(width 0.1524)
				(type default)
			)
			(layer "F.SilkS")
		)
		(fp_line
			(start -0.67945 -0.305054)
			(end -0.12065 -0.305054)
			(stroke
				(width 0.1)
				(type default)
			)
			(layer "F.Fab")
		)
		(fp_line
			(start -0.67945 0.3048)
			(end -0.67945 -0.305054)
			(stroke
				(width 0.1)
				(type default)
			)
			(layer "F.Fab")
		)
		(fp_line
			(start -0.12065 -0.305054)
			(end -0.12065 -0.2794)
			(stroke
				(width 0.1)
				(type default)
			)
			(layer "F.Fab")
		)
		(fp_line
			(start -0.12065 -0.2794)
			(end 0.12065 -0.2794)
			(stroke
				(width 0.1)
				(type default)
			)
			(layer "F.Fab")
		)
		(fp_line
			(start -0.12065 0.2794)
			(end -0.12065 0.3048)
			(stroke
				(width 0.1)
				(type default)
			)
			(layer "F.Fab")
		)
		(fp_line
			(start -0.12065 0.3048)
			(end -0.67945 0.3048)
			(stroke
				(width 0.1)
				(type default)
			)
			(layer "F.Fab")
		)
		(fp_line
			(start 0.120396 0.2794)
			(end -0.12065 0.2794)
			(stroke
				(width 0.1)
				(type default)
			)
			(layer "F.Fab")
		)
		(fp_line
			(start 0.120396 0.3048)
			(end 0.120396 0.2794)
			(stroke
				(width 0.1)
				(type default)
			)
			(layer "F.Fab")
		)
		(fp_line
			(start 0.12065 -0.3048)
			(end 0.67945 -0.3048)
			(stroke
				(width 0.1)
				(type default)
			)
			(layer "F.Fab")
		)
		(fp_line
			(start 0.12065 -0.2794)
			(end 0.12065 -0.3048)
			(stroke
				(width 0.1)
				(type default)
			)
			(layer "F.Fab")
		)
		(fp_line
			(start 0.67945 -0.3048)
			(end 0.67945 0.3048)
			(stroke
				(width 0.1)
				(type default)
			)
			(layer "F.Fab")
		)
		(fp_line
			(start 0.67945 0.3048)
			(end 0.120396 0.3048)
			(stroke
				(width 0.1)
				(type default)
			)
			(layer "F.Fab")
		)
		(pad "1" smd circle
			(at -0.40005 0)
			(size 0 0)
			(layers "F.Cu" "F.Mask" "F.Paste")
			(net "P12V_SSD3")
		)
		(pad "2" smd circle
			(at 0.40005 0)
			(size 0 0)
			(layers "F.Cu" "F.Mask" "F.Paste")
			(net "GND")
		)
	)
	(footprint ""
		(layer "F.Cu")
		(at 95.105728 -242.776248 180)
		(property "Reference" "R817"
			(at 0 0 180)
			(layer "F.SilkS")
			(hide yes)
			(effects
				(font
					(size 1.27 1.27)
				)
			)
		)
		(property "Value" ""
			(at 0 0 180)
			(layer "F.Fab")
			(effects
				(font
					(size 1.27 1.27)
				)
			)
		)
		(duplicate_pad_numbers_are_jumpers no)
		(fp_line
			(start 0.7874 0.4064)
			(end -0.7874 0.4064)
			(stroke
				(width 0.1524)
				(type default)
			)
			(layer "F.SilkS")
		)
		(fp_line
			(start 0.7874 -0.4064)
			(end 0.7874 0.4064)
			(stroke
				(width 0.1524)
				(type default)
			)
			(layer "F.SilkS")
		)
		(fp_line
			(start -0.7874 0.4064)
			(end -0.7874 -0.4064)
			(stroke
				(width 0.1524)
				(type default)
			)
			(layer "F.SilkS")
		)
		(fp_line
			(start -0.7874 -0.4064)
			(end 0.7874 -0.4064)
			(stroke
				(width 0.1524)
				(type default)
			)
			(layer "F.SilkS")
		)
		(fp_line
			(start 0.67945 0.3048)
			(end 0.120396 0.3048)
			(stroke
				(width 0.1)
				(type default)
			)
			(layer "F.Fab")
		)
		(fp_line
			(start 0.67945 -0.3048)
			(end 0.67945 0.3048)
			(stroke
				(width 0.1)
				(type default)
			)
			(layer "F.Fab")
		)
		(fp_line
			(start 0.12065 -0.2794)
			(end 0.12065 -0.3048)
			(stroke
				(width 0.1)
				(type default)
			)
			(layer "F.Fab")
		)
		(fp_line
			(start 0.12065 -0.3048)
			(end 0.67945 -0.3048)
			(stroke
				(width 0.1)
				(type default)
			)
			(layer "F.Fab")
		)
		(fp_line
			(start 0.120396 0.3048)
			(end 0.120396 0.2794)
			(stroke
				(width 0.1)
				(type default)
			)
			(layer "F.Fab")
		)
		(fp_line
			(start 0.120396 0.2794)
			(end -0.12065 0.2794)
			(stroke
				(width 0.1)
				(type default)
			)
			(layer "F.Fab")
		)
		(fp_line
			(start -0.12065 0.3048)
			(end -0.67945 0.3048)
			(stroke
				(width 0.1)
				(type default)
			)
			(layer "F.Fab")
		)
		(fp_line
			(start -0.12065 0.2794)
			(end -0.12065 0.3048)
			(stroke
				(width 0.1)
				(type default)
			)
			(layer "F.Fab")
		)
		(fp_line
			(start -0.12065 -0.2794)
			(end 0.12065 -0.2794)
			(stroke
				(width 0.1)
				(type default)
			)
			(layer "F.Fab")
		)
		(fp_line
			(start -0.12065 -0.305054)
			(end -0.12065 -0.2794)
			(stroke
				(width 0.1)
				(type default)
			)
			(layer "F.Fab")
		)
		(fp_line
			(start -0.67945 0.3048)
			(end -0.67945 -0.305054)
			(stroke
				(width 0.1)
				(type default)
			)
			(layer "F.Fab")
		)
		(fp_line
			(start -0.67945 -0.305054)
			(end -0.12065 -0.305054)
			(stroke
				(width 0.1)
				(type default)
			)
			(layer "F.Fab")
		)
		(pad "1" smd circle
			(at -0.40005 0 180)
			(size 0 0)
			(layers "F.Cu" "F.Mask" "F.Paste")
			(net "PEX_P1V8_ADC_ALERT_N")
		)
		(pad "2" smd circle
			(at 0.40005 0 180)
			(size 0 0)
			(layers "F.Cu" "F.Mask" "F.Paste")
			(net "PEX_ADC_ALERT_N")
		)
	)
	(footprint ""
		(layer "F.Cu")
		(at 365.15167 -124.120656 -90)
		(property "Reference" "PC478"
			(at 0 0 270)
			(layer "F.SilkS")
			(hide yes)
			(effects
				(font
					(size 1.27 1.27)
				)
			)
		)
		(property "Value" ""
			(at 0 0 270)
			(layer "F.Fab")
			(effects
				(font
					(size 1.27 1.27)
				)
			)
		)
		(duplicate_pad_numbers_are_jumpers no)
		(fp_line
			(start -0.7874 0.4064)
			(end -0.7874 -0.4064)
			(stroke
				(width 0.1524)
				(type default)
			)
			(layer "F.SilkS")
		)
		(fp_line
			(start 0.7874 0.4064)
			(end -0.7874 0.4064)
			(stroke
				(width 0.1524)
				(type default)
			)
			(layer "F.SilkS")
		)
		(fp_line
			(start -0.7874 -0.4064)
			(end 0.7874 -0.4064)
			(stroke
				(width 0.1524)
				(type default)
			)
			(layer "F.SilkS")
		)
		(fp_line
			(start 0.7874 -0.4064)
			(end 0.7874 0.4064)
			(stroke
				(width 0.1524)
				(type default)
			)
			(layer "F.SilkS")
		)
		(fp_line
			(start -0.67945 0.3048)
			(end -0.67945 -0.305054)
			(stroke
				(width 0.1)
				(type default)
			)
			(layer "F.Fab")
		)
		(fp_line
			(start -0.12065 0.3048)
			(end -0.67945 0.3048)
			(stroke
				(width 0.1)
				(type default)
			)
			(layer "F.Fab")
		)
		(fp_line
			(start 0.120396 0.3048)
			(end 0.120396 0.2794)
			(stroke
				(width 0.1)
				(type default)
			)
			(layer "F.Fab")
		)
		(fp_line
			(start 0.67945 0.3048)
			(end 0.120396 0.3048)
			(stroke
				(width 0.1)
				(type default)
			)
			(layer "F.Fab")
		)
		(fp_line
			(start -0.12065 0.2794)
			(end -0.12065 0.3048)
			(stroke
				(width 0.1)
				(type default)
			)
			(layer "F.Fab")
		)
		(fp_line
			(start 0.120396 0.2794)
			(end -0.12065 0.2794)
			(stroke
				(width 0.1)
				(type default)
			)
			(layer "F.Fab")
		)
		(fp_line
			(start -0.12065 -0.2794)
			(end 0.12065 -0.2794)
			(stroke
				(width 0.1)
				(type default)
			)
			(layer "F.Fab")
		)
		(fp_line
			(start 0.12065 -0.2794)
			(end 0.12065 -0.3048)
			(stroke
				(width 0.1)
				(type default)
			)
			(layer "F.Fab")
		)
		(fp_line
			(start 0.12065 -0.3048)
			(end 0.67945 -0.3048)
			(stroke
				(width 0.1)
				(type default)
			)
			(layer "F.Fab")
		)
		(fp_line
			(start 0.67945 -0.3048)
			(end 0.67945 0.3048)
			(stroke
				(width 0.1)
				(type default)
			)
			(layer "F.Fab")
		)
		(fp_line
			(start -0.67945 -0.305054)
			(end -0.12065 -0.305054)
			(stroke
				(width 0.1)
				(type default)
			)
			(layer "F.Fab")
		)
		(fp_line
			(start -0.12065 -0.305054)
			(end -0.12065 -0.2794)
			(stroke
				(width 0.1)
				(type default)
			)
			(layer "F.Fab")
		)
		(pad "1" smd circle
			(at -0.40005 0 270)
			(size 0 0)
			(layers "F.Cu" "F.Mask" "F.Paste")
			(net "P3V3_NIC6")
		)
		(pad "2" smd circle
			(at 0.40005 0 270)
			(size 0 0)
			(layers "F.Cu" "F.Mask" "F.Paste")
			(net "GND")
		)
	)
	(footprint ""
		(layer "F.Cu")
		(at 288.029142 -117.5512)
		(property "Reference" "R210"
			(at 0 0 0)
			(layer "F.SilkS")
			(hide yes)
			(effects
				(font
					(size 1.27 1.27)
				)
			)
		)
		(property "Value" ""
			(at 0 0 0)
			(layer "F.Fab")
			(effects
				(font
					(size 1.27 1.27)
				)
			)
		)
		(duplicate_pad_numbers_are_jumpers no)
		(fp_line
			(start -0.7874 -0.4064)
			(end 0.7874 -0.4064)
			(stroke
				(width 0.1524)
				(type default)
			)
			(layer "F.SilkS")
		)
		(fp_line
			(start -0.7874 0.4064)
			(end -0.7874 -0.4064)
			(stroke
				(width 0.1524)
				(type default)
			)
			(layer "F.SilkS")
		)
		(fp_line
			(start 0.7874 -0.4064)
			(end 0.7874 0.4064)
			(stroke
				(width 0.1524)
				(type default)
			)
			(layer "F.SilkS")
		)
		(fp_line
			(start 0.7874 0.4064)
			(end -0.7874 0.4064)
			(stroke
				(width 0.1524)
				(type default)
			)
			(layer "F.SilkS")
		)
		(fp_line
			(start -0.67945 -0.305054)
			(end -0.12065 -0.305054)
			(stroke
				(width 0.1)
				(type default)
			)
			(layer "F.Fab")
		)
		(fp_line
			(start -0.67945 0.3048)
			(end -0.67945 -0.305054)
			(stroke
				(width 0.1)
				(type default)
			)
			(layer "F.Fab")
		)
		(fp_line
			(start -0.12065 -0.305054)
			(end -0.12065 -0.2794)
			(stroke
				(width 0.1)
				(type default)
			)
			(layer "F.Fab")
		)
		(fp_line
			(start -0.12065 -0.2794)
			(end 0.12065 -0.2794)
			(stroke
				(width 0.1)
				(type default)
			)
			(layer "F.Fab")
		)
		(fp_line
			(start -0.12065 0.2794)
			(end -0.12065 0.3048)
			(stroke
				(width 0.1)
				(type default)
			)
			(layer "F.Fab")
		)
		(fp_line
			(start -0.12065 0.3048)
			(end -0.67945 0.3048)
			(stroke
				(width 0.1)
				(type default)
			)
			(layer "F.Fab")
		)
		(fp_line
			(start 0.120396 0.2794)
			(end -0.12065 0.2794)
			(stroke
				(width 0.1)
				(type default)
			)
			(layer "F.Fab")
		)
		(fp_line
			(start 0.120396 0.3048)
			(end 0.120396 0.2794)
			(stroke
				(width 0.1)
				(type default)
			)
			(layer "F.Fab")
		)
		(fp_line
			(start 0.12065 -0.3048)
			(end 0.67945 -0.3048)
			(stroke
				(width 0.1)
				(type default)
			)
			(layer "F.Fab")
		)
		(fp_line
			(start 0.12065 -0.2794)
			(end 0.12065 -0.3048)
			(stroke
				(width 0.1)
				(type default)
			)
			(layer "F.Fab")
		)
		(fp_line
			(start 0.67945 -0.3048)
			(end 0.67945 0.3048)
			(stroke
				(width 0.1)
				(type default)
			)
			(layer "F.Fab")
		)
		(fp_line
			(start 0.67945 0.3048)
			(end 0.120396 0.3048)
			(stroke
				(width 0.1)
				(type default)
			)
			(layer "F.Fab")
		)
		(pad "1" smd circle
			(at -0.40005 0)
			(size 0 0)
			(layers "F.Cu" "F.Mask" "F.Paste")
			(net "PRSNTB1_NIC4_N")
		)
		(pad "2" smd circle
			(at 0.40005 0)
			(size 0 0)
			(layers "F.Cu" "F.Mask" "F.Paste")
			(net "P3V3_AUX")
		)
	)
	(footprint ""
		(layer "F.Cu")
		(at 384.51282 -356.244906 90)
		(property "Reference" "C775"
			(at 0 0 90)
			(layer "F.SilkS")
			(hide yes)
			(effects
				(font
					(size 1.27 1.27)
				)
			)
		)
		(property "Value" ""
			(at 0 0 90)
			(layer "F.Fab")
			(effects
				(font
					(size 1.27 1.27)
				)
			)
		)
		(duplicate_pad_numbers_are_jumpers no)
		(fp_line
			(start 0.299974 -0.150114)
			(end 0.299974 0.150114)
			(stroke
				(width 0.1)
				(type default)
			)
			(layer "F.Fab")
		)
		(fp_line
			(start -0.299974 -0.150114)
			(end 0.299974 -0.150114)
			(stroke
				(width 0.1)
				(type default)
			)
			(layer "F.Fab")
		)
		(fp_line
			(start 0.299974 0.150114)
			(end -0.299974 0.150114)
			(stroke
				(width 0.1)
				(type default)
			)
			(layer "F.Fab")
		)
		(fp_line
			(start -0.299974 0.150114)
			(end -0.299974 -0.150114)
			(stroke
				(width 0.1)
				(type default)
			)
			(layer "F.Fab")
		)
		(pad "1" smd rect
			(at -0.2667 0 90)
			(size 0.3048 0.381)
			(layers "F.Cu" "F.Mask" "F.Paste")
			(net "P5E_PEX3_STN6_TX_DN<105>")
		)
		(pad "2" smd rect
			(at 0.2667 0 90)
			(size 0.3048 0.381)
			(layers "F.Cu" "F.Mask" "F.Paste")
			(net "P5E_PEX3_STN6_TX_C_DN<105>")
		)
	)
	(footprint ""
		(layer "F.Cu")
		(at 238.124746 -115.682268)
		(property "Reference" "PR6900"
			(at 0 0 0)
			(layer "F.SilkS")
			(hide yes)
			(effects
				(font
					(size 1.27 1.27)
				)
			)
		)
		(property "Value" ""
			(at 0 0 0)
			(layer "F.Fab")
			(effects
				(font
					(size 1.27 1.27)
				)
			)
		)
		(duplicate_pad_numbers_are_jumpers no)
		(fp_line
			(start -0.7874 -0.4064)
			(end 0.7874 -0.4064)
			(stroke
				(width 0.1524)
				(type default)
			)
			(layer "F.SilkS")
		)
		(fp_line
			(start -0.7874 0.4064)
			(end -0.7874 -0.4064)
			(stroke
				(width 0.1524)
				(type default)
			)
			(layer "F.SilkS")
		)
		(fp_line
			(start 0.7874 -0.4064)
			(end 0.7874 0.4064)
			(stroke
				(width 0.1524)
				(type default)
			)
			(layer "F.SilkS")
		)
		(fp_line
			(start 0.7874 0.4064)
			(end -0.7874 0.4064)
			(stroke
				(width 0.1524)
				(type default)
			)
			(layer "F.SilkS")
		)
		(fp_line
			(start -0.67945 -0.305054)
			(end -0.12065 -0.305054)
			(stroke
				(width 0.1)
				(type default)
			)
			(layer "F.Fab")
		)
		(fp_line
			(start -0.67945 0.3048)
			(end -0.67945 -0.305054)
			(stroke
				(width 0.1)
				(type default)
			)
			(layer "F.Fab")
		)
		(fp_line
			(start -0.12065 -0.305054)
			(end -0.12065 -0.2794)
			(stroke
				(width 0.1)
				(type default)
			)
			(layer "F.Fab")
		)
		(fp_line
			(start -0.12065 -0.2794)
			(end 0.12065 -0.2794)
			(stroke
				(width 0.1)
				(type default)
			)
			(layer "F.Fab")
		)
		(fp_line
			(start -0.12065 0.2794)
			(end -0.12065 0.3048)
			(stroke
				(width 0.1)
				(type default)
			)
			(layer "F.Fab")
		)
		(fp_line
			(start -0.12065 0.3048)
			(end -0.67945 0.3048)
			(stroke
				(width 0.1)
				(type default)
			)
			(layer "F.Fab")
		)
		(fp_line
			(start 0.120396 0.2794)
			(end -0.12065 0.2794)
			(stroke
				(width 0.1)
				(type default)
			)
			(layer "F.Fab")
		)
		(fp_line
			(start 0.120396 0.3048)
			(end 0.120396 0.2794)
			(stroke
				(width 0.1)
				(type default)
			)
			(layer "F.Fab")
		)
		(fp_line
			(start 0.12065 -0.3048)
			(end 0.67945 -0.3048)
			(stroke
				(width 0.1)
				(type default)
			)
			(layer "F.Fab")
		)
		(fp_line
			(start 0.12065 -0.2794)
			(end 0.12065 -0.3048)
			(stroke
				(width 0.1)
				(type default)
			)
			(layer "F.Fab")
		)
		(fp_line
			(start 0.67945 -0.3048)
			(end 0.67945 0.3048)
			(stroke
				(width 0.1)
				(type default)
			)
			(layer "F.Fab")
		)
		(fp_line
			(start 0.67945 0.3048)
			(end 0.120396 0.3048)
			(stroke
				(width 0.1)
				(type default)
			)
			(layer "F.Fab")
		)
		(pad "1" smd circle
			(at -0.40005 0)
			(size 0 0)
			(layers "F.Cu" "F.Mask" "F.Paste")
			(net "P12V_NIC3_CO_ISET")
		)
		(pad "2" smd circle
			(at 0.40005 0)
			(size 0 0)
			(layers "F.Cu" "F.Mask" "F.Paste")
			(net "GND")
		)
	)
	(footprint ""
		(layer "F.Cu")
		(at 234.271058 -83.718908)
		(property "Reference" "R6288"
			(at 0 0 0)
			(layer "F.SilkS")
			(hide yes)
			(effects
				(font
					(size 1.27 1.27)
				)
			)
		)
		(property "Value" ""
			(at 0 0 0)
			(layer "F.Fab")
			(effects
				(font
					(size 1.27 1.27)
				)
			)
		)
		(duplicate_pad_numbers_are_jumpers no)
		(fp_line
			(start -0.7874 0.4064)
			(end -0.7874 -0.4064)
			(stroke
				(width 0.1524)
				(type default)
			)
			(layer "F.SilkS")
		)
		(fp_line
			(start -0.02286 -0.4064)
			(end 0.7874 -0.4064)
			(stroke
				(width 0.1524)
				(type default)
			)
			(layer "F.SilkS")
		)
		(fp_line
			(start 0.7874 -0.4064)
			(end 0.7874 0.4064)
			(stroke
				(width 0.1524)
				(type default)
			)
			(layer "F.SilkS")
		)
		(fp_line
			(start 0.7874 0.4064)
			(end -0.7874 0.4064)
			(stroke
				(width 0.1524)
				(type default)
			)
			(layer "F.SilkS")
		)
		(fp_line
			(start -0.67945 -0.305054)
			(end -0.12065 -0.305054)
			(stroke
				(width 0.1)
				(type default)
			)
			(layer "F.Fab")
		)
		(fp_line
			(start -0.67945 0.3048)
			(end -0.67945 -0.305054)
			(stroke
				(width 0.1)
				(type default)
			)
			(layer "F.Fab")
		)
		(fp_line
			(start -0.12065 -0.305054)
			(end -0.12065 -0.2794)
			(stroke
				(width 0.1)
				(type default)
			)
			(layer "F.Fab")
		)
		(fp_line
			(start -0.12065 -0.2794)
			(end 0.12065 -0.2794)
			(stroke
				(width 0.1)
				(type default)
			)
			(layer "F.Fab")
		)
		(fp_line
			(start -0.12065 0.2794)
			(end -0.12065 0.3048)
			(stroke
				(width 0.1)
				(type default)
			)
			(layer "F.Fab")
		)
		(fp_line
			(start -0.12065 0.3048)
			(end -0.67945 0.3048)
			(stroke
				(width 0.1)
				(type default)
			)
			(layer "F.Fab")
		)
		(fp_line
			(start 0.120396 0.2794)
			(end -0.12065 0.2794)
			(stroke
				(width 0.1)
				(type default)
			)
			(layer "F.Fab")
		)
		(fp_line
			(start 0.120396 0.3048)
			(end 0.120396 0.2794)
			(stroke
				(width 0.1)
				(type default)
			)
			(layer "F.Fab")
		)
		(fp_line
			(start 0.12065 -0.3048)
			(end 0.67945 -0.3048)
			(stroke
				(width 0.1)
				(type default)
			)
			(layer "F.Fab")
		)
		(fp_line
			(start 0.12065 -0.2794)
			(end 0.12065 -0.3048)
			(stroke
				(width 0.1)
				(type default)
			)
			(layer "F.Fab")
		)
		(fp_line
			(start 0.67945 -0.3048)
			(end 0.67945 0.3048)
			(stroke
				(width 0.1)
				(type default)
			)
			(layer "F.Fab")
		)
		(fp_line
			(start 0.67945 0.3048)
			(end 0.120396 0.3048)
			(stroke
				(width 0.1)
				(type default)
			)
			(layer "F.Fab")
		)
		(pad "1" smd rect
			(at -0.40005 0 180)
			(size 0.4572 0.508)
			(layers "F.Cu" "F.Mask" "F.Paste")
			(net "USB2_FT4232_SDB_DP")
		)
		(pad "2" smd rect
			(at 0.40005 0 180)
			(size 0.4572 0.508)
			(layers "F.Cu" "F.Mask" "F.Paste")
			(net "GND")
		)
	)
)
